(kicad_pcb
	(version 20260206)
	(generator "pcbnew")
	(generator_version "10.0")
	(general
		(thickness 1.6)
		(legacy_teardrops no)
	)
	(paper "A4")
	(title_block
		(title "netronome-mezz — pcbd0082-001_rev01_jul9_a.brd")
		(comment 1 "Open CloudServer (Microsoft) / footprint 225 of 714 (U1), pads 1-118 of 1022")
	)
	(layers
		(0 "F.Cu" signal "TOP")
		(4 "In1.Cu" signal "02_GND")
		(6 "In2.Cu" signal "03_SIG")
		(8 "In3.Cu" signal "04_SIG")
		(10 "In4.Cu" signal "05_GND")
		(12 "In5.Cu" signal "06_PWR1")
		(14 "In6.Cu" signal "07_SIG")
		(16 "In7.Cu" signal "08_SIG")
		(18 "In8.Cu" signal "09_GND")
		(2 "B.Cu" signal "BOTTOM")
		(9 "F.Adhes" user "F.Adhesive")
		(11 "B.Adhes" user "B.Adhesive")
		(13 "F.Paste" user "Package Geometry/Pastemask Top")
		(15 "B.Paste" user "Package Geometry/Pastemask Bottom")
		(5 "F.SilkS" user "Ref Des/Silkscreen Top")
		(7 "B.SilkS" user "Ref Des/Silkscreen Bottom")
		(1 "F.Mask" user "Board Geometry/Soldermask Top")
		(3 "B.Mask" user "Board Geometry/Soldermask Bottom")
		(17 "Dwgs.User" user "User.Drawings")
		(19 "Cmts.User" user "User.Comments")
		(21 "Eco1.User" user "User.Eco1")
		(23 "Eco2.User" user "User.Eco2")
		(25 "Edge.Cuts" user "Board Geometry/Outline")
		(27 "Margin" user)
		(31 "F.CrtYd" user "Package Geometry/Place Bound Top")
		(29 "B.CrtYd" user "Package Geometry/Place Bound Bottom")
		(35 "F.Fab" user "Ref Des/Assembly Top")
		(33 "B.Fab" user "Ref Des/Assembly Bottom")
		(45 "User.4" user "COMPVAL_TYPE_BOTTOM")
	)
	(footprint ""
		(layer "F.Cu")
		(at 54.737 18.542 180)
		(property "Reference" "U1"
			(at -12.192 17.9705 0)
			(unlocked yes)
			(layer "F.SilkS")
			(effects
				(font
					(size 1.27 0.9652)
					(thickness 0.1524)
				)
				(justify left)
			)
		)
		(property "Value" "*"
			(at -0.4826 1.74879 180)
			(unlocked yes)
			(layer "F.Fab")
			(hide yes)
			(effects
				(font
					(size 1.27 0.9652)
					(thickness 0.000001)
				)
				(justify left)
			)
		)
		(property "Device Type" "ICBG0048"
			(at -0.4826 1.74879 180)
			(unlocked yes)
			(layer "F.Fab")
			(hide yes)
			(effects
				(font
					(size 1.27 0.9652)
					(thickness 0.000001)
				)
				(justify left)
			)
		)
		(duplicate_pad_numbers_are_jumpers no)
		(pad "" smd circle
			(at -15.875 18.161 180)
			(size 1.0668 1.0668)
			(layers "F.Cu" "F.Mask" "F.Paste")
		)
		(pad "" smd circle
			(at 12.573 -17.78 180)
			(size 1.0668 1.0668)
			(layers "F.Cu" "F.Mask" "F.Paste")
		)
		(pad "A2" smd circle
			(at -14.499996 -15.499994 180)
			(size 0.6604 0.6604)
			(layers "F.Cu" "F.Mask" "F.Paste")
			(net "GND")
		)
		(pad "A3" smd circle
			(at -13.499998 -15.499994 180)
			(size 0.6604 0.6604)
			(layers "F.Cu" "F.Mask" "F.Paste")
			(net "GND")
		)
		(pad "A4" smd circle
			(at -12.5 -15.499994 180)
			(size 0.508 0.508)
			(layers "F.Cu" "F.Mask" "F.Paste")
			(net "GND")
		)
		(pad "A5" smd circle
			(at -11.500002 -15.499994 180)
			(size 0.508 0.508)
			(layers "F.Cu" "F.Mask" "F.Paste")
			(net "GND")
		)
		(pad "A6" smd circle
			(at -10.500004 -15.499994 180)
			(size 0.508 0.508)
			(layers "F.Cu" "F.Mask" "F.Paste")
			(net "GND")
		)
		(pad "A7" smd circle
			(at -9.500006 -15.499994 180)
			(size 0.508 0.508)
			(layers "F.Cu" "F.Mask" "F.Paste")
			(net "GND")
		)
		(pad "A8" smd circle
			(at -8.500008 -15.499994 180)
			(size 0.508 0.508)
			(layers "F.Cu" "F.Mask" "F.Paste")
			(net "GND")
		)
		(pad "A9" smd circle
			(at -7.50001 -15.499994 180)
			(size 0.508 0.508)
			(layers "F.Cu" "F.Mask" "F.Paste")
			(net "GND")
		)
		(pad "A10" smd circle
			(at -6.500012 -15.499994 180)
			(size 0.508 0.508)
			(layers "F.Cu" "F.Mask" "F.Paste")
			(net "GND")
		)
		(pad "A11" smd circle
			(at -5.499989 -15.499994 180)
			(size 0.508 0.508)
			(layers "F.Cu" "F.Mask" "F.Paste")
			(net "VDD_CORE")
		)
		(pad "A12" smd circle
			(at -4.499991 -15.499994 180)
			(size 0.508 0.508)
			(layers "F.Cu" "F.Mask" "F.Paste")
			(net "GND")
		)
		(pad "A13" smd circle
			(at -3.499993 -15.499994 180)
			(size 0.508 0.508)
			(layers "F.Cu" "F.Mask" "F.Paste")
			(net "VDD_CORE")
		)
		(pad "A14" smd circle
			(at -2.499995 -15.499994 180)
			(size 0.508 0.508)
			(layers "F.Cu" "F.Mask" "F.Paste")
			(net "GND")
		)
		(pad "A15" smd circle
			(at -1.499997 -15.499994 180)
			(size 0.508 0.508)
			(layers "F.Cu" "F.Mask" "F.Paste")
			(net "VDD_CORE")
		)
		(pad "A16" smd circle
			(at -0.499999 -15.499994 180)
			(size 0.508 0.508)
			(layers "F.Cu" "F.Mask" "F.Paste")
			(net "GND")
		)
		(pad "A17" smd circle
			(at 0.499999 -15.499994 180)
			(size 0.508 0.508)
			(layers "F.Cu" "F.Mask" "F.Paste")
			(net "VDD_CORE")
		)
		(pad "A18" smd circle
			(at 1.499997 -15.499994 180)
			(size 0.508 0.508)
			(layers "F.Cu" "F.Mask" "F.Paste")
			(net "GND")
		)
		(pad "A19" smd circle
			(at 2.499995 -15.499994 180)
			(size 0.508 0.508)
			(layers "F.Cu" "F.Mask" "F.Paste")
			(net "VDD_CORE")
		)
		(pad "A20" smd circle
			(at 3.499993 -15.499994 180)
			(size 0.508 0.508)
			(layers "F.Cu" "F.Mask" "F.Paste")
			(net "GND")
		)
		(pad "A21" smd circle
			(at 4.499991 -15.499994 180)
			(size 0.508 0.508)
			(layers "F.Cu" "F.Mask" "F.Paste")
			(net "VDD_CORE")
		)
		(pad "A22" smd circle
			(at 5.499989 -15.499994 180)
			(size 0.508 0.508)
			(layers "F.Cu" "F.Mask" "F.Paste")
			(net "GND")
		)
		(pad "A23" smd circle
			(at 6.500012 -15.499994 180)
			(size 0.508 0.508)
			(layers "F.Cu" "F.Mask" "F.Paste")
			(net "VDD_CORE")
		)
		(pad "A24" smd circle
			(at 7.50001 -15.499994 180)
			(size 0.508 0.508)
			(layers "F.Cu" "F.Mask" "F.Paste")
			(net "GND")
		)
		(pad "A25" smd circle
			(at 8.500008 -15.499994 180)
			(size 0.508 0.508)
			(layers "F.Cu" "F.Mask" "F.Paste")
			(net "VDD_CORE")
		)
		(pad "A26" smd circle
			(at 9.500006 -15.499994 180)
			(size 0.508 0.508)
			(layers "F.Cu" "F.Mask" "F.Paste")
			(net "GND")
		)
		(pad "A27" smd circle
			(at 10.500004 -15.499994 180)
			(size 0.508 0.508)
			(layers "F.Cu" "F.Mask" "F.Paste")
			(net "_NC_TEST_SCAN_0_OUT33")
		)
		(pad "A28" smd circle
			(at 11.500002 -15.499994 180)
			(size 0.508 0.508)
			(layers "F.Cu" "F.Mask" "F.Paste")
			(net "_NC_TEST_SCAN_0_OUT27")
		)
		(pad "A29" smd circle
			(at 12.5 -15.499994 180)
			(size 0.508 0.508)
			(layers "F.Cu" "F.Mask" "F.Paste")
			(net "_NC_TEST_SCAN_0_OUT30")
		)
		(pad "A30" smd circle
			(at 13.499998 -15.499994 180)
			(size 0.6604 0.6604)
			(layers "F.Cu" "F.Mask" "F.Paste")
			(net "GND")
		)
		(pad "A31" smd circle
			(at 14.499996 -15.499994 180)
			(size 0.6604 0.6604)
			(layers "F.Cu" "F.Mask" "F.Paste")
			(net "GND")
		)
		(pad "AA1" smd circle
			(at -15.499994 4.499991 180)
			(size 0.508 0.508)
			(layers "F.Cu" "F.Mask" "F.Paste")
			(net "DDR0_32A_DQ19")
		)
		(pad "AA2" smd circle
			(at -14.499996 4.499991 180)
			(size 0.508 0.508)
			(layers "F.Cu" "F.Mask" "F.Paste")
			(net "DDR_VDDQ")
		)
		(pad "AA3" smd circle
			(at -13.499998 4.499991 180)
			(size 0.508 0.508)
			(layers "F.Cu" "F.Mask" "F.Paste")
			(net "DDR0_32A_DQ16")
		)
		(pad "AA4" smd circle
			(at -12.5 4.499991 180)
			(size 0.508 0.508)
			(layers "F.Cu" "F.Mask" "F.Paste")
			(net "DDR0_32A_DQ21")
		)
		(pad "AA5" smd circle
			(at -11.500002 4.499991 180)
			(size 0.508 0.508)
			(layers "F.Cu" "F.Mask" "F.Paste")
			(net "DDR_VDDQ")
		)
		(pad "AA6" smd circle
			(at -10.500004 4.499991 180)
			(size 0.508 0.508)
			(layers "F.Cu" "F.Mask" "F.Paste")
			(net "DDR0_32A_DQ18")
		)
		(pad "AA7" smd circle
			(at -9.500006 4.499991 180)
			(size 0.508 0.508)
			(layers "F.Cu" "F.Mask" "F.Paste")
			(net "DDR0_32A_ODT0")
		)
		(pad "AA8" smd circle
			(at -8.500008 4.499991 180)
			(size 0.508 0.508)
			(layers "F.Cu" "F.Mask" "F.Paste")
			(net "DDR_VDDQ")
		)
		(pad "AA9" smd circle
			(at -7.50001 4.499991 180)
			(size 0.508 0.508)
			(layers "F.Cu" "F.Mask" "F.Paste")
			(net "A_AZQ")
		)
		(pad "AA10" smd circle
			(at -6.500012 4.499991 180)
			(size 0.508 0.508)
			(layers "F.Cu" "F.Mask" "F.Paste")
			(net "VDDA_DDR0_32B")
		)
		(pad "AA11" smd circle
			(at -5.499989 4.499991 180)
			(size 0.508 0.508)
			(layers "F.Cu" "F.Mask" "F.Paste")
			(net "VDD_CORE")
		)
		(pad "AA12" smd circle
			(at -4.499991 4.499991 180)
			(size 0.508 0.508)
			(layers "F.Cu" "F.Mask" "F.Paste")
			(net "GND")
		)
		(pad "AA13" smd circle
			(at -3.499993 4.499991 180)
			(size 0.508 0.508)
			(layers "F.Cu" "F.Mask" "F.Paste")
			(net "VDD_CORE")
		)
		(pad "AA14" smd circle
			(at -2.499995 4.499991 180)
			(size 0.508 0.508)
			(layers "F.Cu" "F.Mask" "F.Paste")
			(net "GND")
		)
		(pad "AA15" smd circle
			(at -1.499997 4.499991 180)
			(size 0.508 0.508)
			(layers "F.Cu" "F.Mask" "F.Paste")
			(net "VDD_CORE")
		)
		(pad "AA16" smd circle
			(at -0.499999 4.499991 180)
			(size 0.508 0.508)
			(layers "F.Cu" "F.Mask" "F.Paste")
			(net "GND")
		)
		(pad "AA17" smd circle
			(at 0.499999 4.499991 180)
			(size 0.508 0.508)
			(layers "F.Cu" "F.Mask" "F.Paste")
			(net "VDD_CORE")
		)
		(pad "AA18" smd circle
			(at 1.499997 4.499991 180)
			(size 0.508 0.508)
			(layers "F.Cu" "F.Mask" "F.Paste")
			(net "GND")
		)
		(pad "AA19" smd circle
			(at 2.499995 4.499991 180)
			(size 0.508 0.508)
			(layers "F.Cu" "F.Mask" "F.Paste")
			(net "VDD_CORE")
		)
		(pad "AA20" smd circle
			(at 3.499993 4.499991 180)
			(size 0.508 0.508)
			(layers "F.Cu" "F.Mask" "F.Paste")
			(net "GND")
		)
		(pad "AA21" smd circle
			(at 4.499991 4.499991 180)
			(size 0.508 0.508)
			(layers "F.Cu" "F.Mask" "F.Paste")
			(net "VDD_CORE")
		)
		(pad "AA22" smd circle
			(at 5.499989 4.499991 180)
			(size 0.508 0.508)
			(layers "F.Cu" "F.Mask" "F.Paste")
			(net "GND")
		)
		(pad "AA23" smd circle
			(at 6.500012 4.499991 180)
			(size 0.508 0.508)
			(layers "F.Cu" "F.Mask" "F.Paste")
			(net "VDD_CORE")
		)
		(pad "AA24" smd circle
			(at 7.50001 4.499991 180)
			(size 0.508 0.508)
			(layers "F.Cu" "F.Mask" "F.Paste")
			(net "GND")
		)
		(pad "AA25" smd circle
			(at 8.500008 4.499991 180)
			(size 0.508 0.508)
			(layers "F.Cu" "F.Mask" "F.Paste")
			(net "VDD_CORE")
		)
		(pad "AA26" smd circle
			(at 9.500006 4.499991 180)
			(size 0.508 0.508)
			(layers "F.Cu" "F.Mask" "F.Paste")
			(net "GND")
		)
		(pad "AA27" smd circle
			(at 10.500004 4.499991 180)
			(size 0.508 0.508)
			(layers "F.Cu" "F.Mask" "F.Paste")
			(net "VDD_3.3V")
		)
		(pad "AA28" smd circle
			(at 11.500002 4.499991 180)
			(size 0.508 0.508)
			(layers "F.Cu" "F.Mask" "F.Paste")
			(net "NFP_CPLD_INT_L")
		)
		(pad "AA29" smd circle
			(at 12.5 4.499991 180)
			(size 0.508 0.508)
			(layers "F.Cu" "F.Mask" "F.Paste")
			(net "NFP_ARM_SPI_FLASH_WP_L")
		)
		(pad "AA30" smd circle
			(at 13.499998 4.499991 180)
			(size 0.508 0.508)
			(layers "F.Cu" "F.Mask" "F.Paste")
			(net "_NC_NFP_GPIO6")
		)
		(pad "AA31" smd circle
			(at 14.499996 4.499991 180)
			(size 0.508 0.508)
			(layers "F.Cu" "F.Mask" "F.Paste")
			(net "NFP_JTAG_ARM_TCK")
		)
		(pad "AA32" smd circle
			(at 15.499994 4.499991 180)
			(size 0.508 0.508)
			(layers "F.Cu" "F.Mask" "F.Paste")
			(net "NFP_JTAG_ARM_TMS")
		)
		(pad "AB1" smd circle
			(at -15.499994 5.499989 180)
			(size 0.508 0.508)
			(layers "F.Cu" "F.Mask" "F.Paste")
			(net "DDR0_32A_DQ17")
		)
		(pad "AB2" smd circle
			(at -14.499996 5.499989 180)
			(size 0.508 0.508)
			(layers "F.Cu" "F.Mask" "F.Paste")
			(net "GND")
		)
		(pad "AB3" smd circle
			(at -13.499998 5.499989 180)
			(size 0.508 0.508)
			(layers "F.Cu" "F.Mask" "F.Paste")
			(net "DDR0_32A_DQ8")
		)
		(pad "AB4" smd circle
			(at -12.5 5.499989 180)
			(size 0.508 0.508)
			(layers "F.Cu" "F.Mask" "F.Paste")
			(net "DDR0_32A_DQ10")
		)
		(pad "AB5" smd circle
			(at -11.500002 5.499989 180)
			(size 0.508 0.508)
			(layers "F.Cu" "F.Mask" "F.Paste")
			(net "GND")
		)
		(pad "AB6" smd circle
			(at -10.500004 5.499989 180)
			(size 0.508 0.508)
			(layers "F.Cu" "F.Mask" "F.Paste")
			(net "DDR0_32A_BA1")
		)
		(pad "AB7" smd circle
			(at -9.500006 5.499989 180)
			(size 0.508 0.508)
			(layers "F.Cu" "F.Mask" "F.Paste")
			(net "DDR0_32A_RAS_L")
		)
		(pad "AB8" smd circle
			(at -8.500008 5.499989 180)
			(size 0.508 0.508)
			(layers "F.Cu" "F.Mask" "F.Paste")
			(net "GND")
		)
		(pad "AB9" smd circle
			(at -7.50001 5.499989 180)
			(size 0.508 0.508)
			(layers "F.Cu" "F.Mask" "F.Paste")
			(net "DDR0_32A_CAS_L")
		)
		(pad "AB10" smd circle
			(at -6.500012 5.499989 180)
			(size 0.508 0.508)
			(layers "F.Cu" "F.Mask" "F.Paste")
			(net "VDDA_DDR0_32A")
		)
		(pad "AB11" smd circle
			(at -5.499989 5.499989 180)
			(size 0.508 0.508)
			(layers "F.Cu" "F.Mask" "F.Paste")
			(net "GND")
		)
		(pad "AB12" smd circle
			(at -4.499991 5.499989 180)
			(size 0.508 0.508)
			(layers "F.Cu" "F.Mask" "F.Paste")
			(net "VDD_CORE")
		)
		(pad "AB13" smd circle
			(at -3.499993 5.499989 180)
			(size 0.508 0.508)
			(layers "F.Cu" "F.Mask" "F.Paste")
			(net "GND")
		)
		(pad "AB14" smd circle
			(at -2.499995 5.499989 180)
			(size 0.508 0.508)
			(layers "F.Cu" "F.Mask" "F.Paste")
			(net "VDD_CORE")
		)
		(pad "AB15" smd circle
			(at -1.499997 5.499989 180)
			(size 0.508 0.508)
			(layers "F.Cu" "F.Mask" "F.Paste")
			(net "GND")
		)
		(pad "AB16" smd circle
			(at -0.499999 5.499989 180)
			(size 0.508 0.508)
			(layers "F.Cu" "F.Mask" "F.Paste")
			(net "VDD_CORE")
		)
		(pad "AB17" smd circle
			(at 0.499999 5.499989 180)
			(size 0.508 0.508)
			(layers "F.Cu" "F.Mask" "F.Paste")
			(net "GND")
		)
		(pad "AB18" smd circle
			(at 1.499997 5.499989 180)
			(size 0.508 0.508)
			(layers "F.Cu" "F.Mask" "F.Paste")
			(net "VDD_CORE")
		)
		(pad "AB19" smd circle
			(at 2.499995 5.499989 180)
			(size 0.508 0.508)
			(layers "F.Cu" "F.Mask" "F.Paste")
			(net "GND")
		)
		(pad "AB20" smd circle
			(at 3.499993 5.499989 180)
			(size 0.508 0.508)
			(layers "F.Cu" "F.Mask" "F.Paste")
			(net "VDD_CORE")
		)
		(pad "AB21" smd circle
			(at 4.499991 5.499989 180)
			(size 0.508 0.508)
			(layers "F.Cu" "F.Mask" "F.Paste")
			(net "GND")
		)
		(pad "AB22" smd circle
			(at 5.499989 5.499989 180)
			(size 0.508 0.508)
			(layers "F.Cu" "F.Mask" "F.Paste")
			(net "VDD_CORE")
		)
		(pad "AB23" smd circle
			(at 6.500012 5.499989 180)
			(size 0.508 0.508)
			(layers "F.Cu" "F.Mask" "F.Paste")
			(net "GND")
		)
		(pad "AB24" smd circle
			(at 7.50001 5.499989 180)
			(size 0.508 0.508)
			(layers "F.Cu" "F.Mask" "F.Paste")
			(net "VDD_CORE")
		)
		(pad "AB25" smd circle
			(at 8.500008 5.499989 180)
			(size 0.508 0.508)
			(layers "F.Cu" "F.Mask" "F.Paste")
			(net "GND")
		)
		(pad "AB26" smd circle
			(at 9.500006 5.499989 180)
			(size 0.508 0.508)
			(layers "F.Cu" "F.Mask" "F.Paste")
			(net "VDD_3.3V")
		)
		(pad "AB27" smd circle
			(at 10.500004 5.499989 180)
			(size 0.508 0.508)
			(layers "F.Cu" "F.Mask" "F.Paste")
			(net "CPLD_PGRM_JTAG_SEL")
		)
		(pad "AB28" smd circle
			(at 11.500002 5.499989 180)
			(size 0.508 0.508)
			(layers "F.Cu" "F.Mask" "F.Paste")
			(net "_PSU_I2C_SDA")
		)
		(pad "AB29" smd circle
			(at 12.5 5.499989 180)
			(size 0.508 0.508)
			(layers "F.Cu" "F.Mask" "F.Paste")
			(net "_PSU_I2C_SCL")
		)
		(pad "AB30" smd circle
			(at 13.499998 5.499989 180)
			(size 0.508 0.508)
			(layers "F.Cu" "F.Mask" "F.Paste")
			(net "NFP_FAIL_SAFE_BOOT_L")
		)
		(pad "AB31" smd circle
			(at 14.499996 5.499989 180)
			(size 0.508 0.508)
			(layers "F.Cu" "F.Mask" "F.Paste")
			(net "PGRM_JTAG_TRST_L")
		)
		(pad "AB32" smd circle
			(at 15.499994 5.499989 180)
			(size 0.508 0.508)
			(layers "F.Cu" "F.Mask" "F.Paste")
			(net "PGRM_JTAG_TCK")
		)
		(pad "AC1" smd circle
			(at -15.499994 6.500012 180)
			(size 0.508 0.508)
			(layers "F.Cu" "F.Mask" "F.Paste")
			(net "DDR0_32A_DQ11")
		)
		(pad "AC2" smd circle
			(at -14.499996 6.500012 180)
			(size 0.508 0.508)
			(layers "F.Cu" "F.Mask" "F.Paste")
			(net "DDR0_32A_DQ13")
		)
		(pad "AC3" smd circle
			(at -13.499998 6.500012 180)
			(size 0.508 0.508)
			(layers "F.Cu" "F.Mask" "F.Paste")
			(net "DDR0_32A_DQS1_P")
		)
		(pad "AC4" smd circle
			(at -12.5 6.500012 180)
			(size 0.508 0.508)
			(layers "F.Cu" "F.Mask" "F.Paste")
			(net "DDR0_32A_DQS1_N")
		)
		(pad "AC5" smd circle
			(at -11.500002 6.500012 180)
			(size 0.508 0.508)
			(layers "F.Cu" "F.Mask" "F.Paste")
			(net "DDR0_32A_DQ12")
		)
		(pad "AC6" smd circle
			(at -10.500004 6.500012 180)
			(size 0.508 0.508)
			(layers "F.Cu" "F.Mask" "F.Paste")
			(net "DDR0_32A_WE_L")
		)
		(pad "AC7" smd circle
			(at -9.500006 6.500012 180)
			(size 0.508 0.508)
			(layers "F.Cu" "F.Mask" "F.Paste")
			(net "DDR0_32A_CKE0")
		)
		(pad "AC8" smd circle
			(at -8.500008 6.500012 180)
			(size 0.508 0.508)
			(layers "F.Cu" "F.Mask" "F.Paste")
			(net "DDR0_32A_A4")
		)
		(pad "AC9" smd circle
			(at -7.50001 6.500012 180)
			(size 0.508 0.508)
			(layers "F.Cu" "F.Mask" "F.Paste")
			(net "_NC_NFP_DDR0_32A_PLL_ATO")
		)
		(pad "AC10" smd circle
			(at -6.500012 6.500012 180)
			(size 0.508 0.508)
			(layers "F.Cu" "F.Mask" "F.Paste")
			(net "VDDA_DDR0_32A")
		)
		(pad "AC11" smd circle
			(at -5.499989 6.500012 180)
			(size 0.508 0.508)
			(layers "F.Cu" "F.Mask" "F.Paste")
			(net "VDD_CORE")
		)
		(pad "AC12" smd circle
			(at -4.499991 6.500012 180)
			(size 0.508 0.508)
			(layers "F.Cu" "F.Mask" "F.Paste")
			(net "GND")
		)
		(pad "AC13" smd circle
			(at -3.499993 6.500012 180)
			(size 0.508 0.508)
			(layers "F.Cu" "F.Mask" "F.Paste")
			(net "VDD_CORE")
		)
		(pad "AC14" smd circle
			(at -2.499995 6.500012 180)
			(size 0.508 0.508)
			(layers "F.Cu" "F.Mask" "F.Paste")
			(net "GND")
		)
		(pad "AC15" smd circle
			(at -1.499997 6.500012 180)
			(size 0.508 0.508)
			(layers "F.Cu" "F.Mask" "F.Paste")
			(net "VDD_CORE")
		)
		(pad "AC16" smd circle
			(at -0.499999 6.500012 180)
			(size 0.508 0.508)
			(layers "F.Cu" "F.Mask" "F.Paste")
			(net "GND")
		)
		(pad "AC17" smd circle
			(at 0.499999 6.500012 180)
			(size 0.508 0.508)
			(layers "F.Cu" "F.Mask" "F.Paste")
			(net "VDD_CORE")
		)
		(pad "AC18" smd circle
			(at 1.499997 6.500012 180)
			(size 0.508 0.508)
			(layers "F.Cu" "F.Mask" "F.Paste")
			(net "VDDA_PLL")
		)
		(pad "AC19" smd circle
			(at 2.499995 6.500012 180)
			(size 0.508 0.508)
			(layers "F.Cu" "F.Mask" "F.Paste")
			(net "VDD_CORE")
		)
		(pad "AC20" smd circle
			(at 3.499993 6.500012 180)
			(size 0.508 0.508)
			(layers "F.Cu" "F.Mask" "F.Paste")
			(net "GND")
		)
		(pad "AC21" smd circle
			(at 4.499991 6.500012 180)
			(size 0.508 0.508)
			(layers "F.Cu" "F.Mask" "F.Paste")
			(net "VDD_CORE")
		)
		(pad "AC22" smd circle
			(at 5.499989 6.500012 180)
			(size 0.508 0.508)
			(layers "F.Cu" "F.Mask" "F.Paste")
			(net "GND")
		)
	)
)
